(kicad_pcb
	(version 20260206)
	(generator "pcbnew")
	(generator_version "10.0")
	(general
		(thickness 1.6)
		(legacy_teardrops no)
	)
	(paper "A4")
	(title_block
		(title "dpb — 14545-sa.0730WZS0815.brd")
		(comment 1 "Honey Badger (Wiwynn) / footprints 918-925 of 1066")
	)
	(layers
		(0 "F.Cu" signal "TOP")
		(4 "In1.Cu" signal "L2GND")
		(6 "In2.Cu" signal "L3")
		(8 "In3.Cu" signal "L4VCC")
		(10 "In4.Cu" signal "L5VCC")
		(12 "In5.Cu" signal "L6")
		(14 "In6.Cu" signal "L7GND")
		(2 "B.Cu" signal "BOTTOM")
		(9 "F.Adhes" user "F.Adhesive")
		(11 "B.Adhes" user "B.Adhesive")
		(13 "F.Paste" user "Package Geometry/Pastemask Top")
		(15 "B.Paste" user "Package Geometry/Pastemask Bottom")
		(5 "F.SilkS" user "Ref Des/Silkscreen Top")
		(7 "B.SilkS" user "Ref Des/Silkscreen Bottom")
		(1 "F.Mask" user "Board Geometry/Soldermask Top")
		(3 "B.Mask" user "Board Geometry/Soldermask Bottom")
		(17 "Dwgs.User" user "User.Drawings")
		(19 "Cmts.User" user "User.Comments")
		(21 "Eco1.User" user "User.Eco1")
		(23 "Eco2.User" user "User.Eco2")
		(25 "Edge.Cuts" user "Board Geometry/Outline")
		(27 "Margin" user)
		(31 "F.CrtYd" user "Package Geometry/Place Bound Top")
		(29 "B.CrtYd" user "Package Geometry/Place Bound Bottom")
		(35 "F.Fab" user "Ref Des/Assembly Top")
		(33 "B.Fab" user "Ref Des/Assembly Bottom")
	)
	(footprint ""
		(layer "F.Cu")
		(at 241.934746 -27.9527 180)
		(property "Reference" "PR10"
			(at 0 0 180)
			(layer "F.SilkS")
			(hide yes)
			(effects
				(font
					(size 1.27 1.27)
				)
			)
		)
		(property "Value" "100KR2F-L1-GP"
			(at 0.064008 -3.993896 180)
			(unlocked yes)
			(layer "F.Fab")
			(hide yes)
			(effects
				(font
					(size 1.016 1.016)
					(thickness 0.1524)
				)
			)
		)
		(property "Device Type" "R402H16"
			(at 0.064008 -5.517896 180)
			(unlocked yes)
			(layer "F.Fab")
			(hide yes)
			(effects
				(font
					(size 1.016 1.016)
					(thickness 0.1524)
				)
			)
		)
		(duplicate_pad_numbers_are_jumpers no)
		(fp_line
			(start 0.508 -0.9398)
			(end -0.508 -0.9398)
			(stroke
				(width 0.1524)
				(type default)
			)
			(layer "F.SilkS")
		)
		(fp_line
			(start -0.508 -0.9398)
			(end -0.508 0.9398)
			(stroke
				(width 0.1524)
				(type default)
			)
			(layer "F.SilkS")
		)
		(fp_rect
			(start -0.508 0.9398)
			(end 0.508 -0.9398)
			(stroke
				(width 0)
				(type default)
			)
			(fill no)
			(layer "F.CrtYd")
		)
		(fp_rect
			(start -0.508 0.9398)
			(end 0.508 -0.9398)
			(stroke
				(width 0)
				(type default)
			)
			(fill no)
			(layer "F.Fab")
		)
		(pad "1" smd custom
			(at 0 -0.4445 180)
			(size 0.1397 0.1397)
			(layers "F.Cu" "F.Mask" "F.Paste")
			(net "P5VA_PGD")
			(options
				(clearance outline)
				(anchor circle)
			)
			(primitives
				(gr_poly
					(pts
						(arc
							(start -0.1778 -0.2794)
							(mid -0.249642 -0.249642)
							(end -0.2794 -0.1778)
						)
						(arc
							(start -0.2794 0.1778)
							(mid -0.249642 0.249642)
							(end -0.1778 0.2794)
						)
						(arc
							(start 0.1778 0.2794)
							(mid 0.249642 0.249642)
							(end 0.2794 0.1778)
						)
						(arc
							(start 0.2794 -0.1778)
							(mid 0.249642 -0.249642)
							(end 0.1778 -0.2794)
						)
					)
					(width 0)
					(fill yes)
				)
			)
		)
		(pad "2" smd custom
			(at 0 0.4445 180)
			(size 0.1397 0.1397)
			(layers "F.Cu" "F.Mask" "F.Paste")
			(net "P5VA_MODE_PG")
			(options
				(clearance outline)
				(anchor circle)
			)
			(primitives
				(gr_poly
					(pts
						(arc
							(start -0.1778 -0.2794)
							(mid -0.249642 -0.249642)
							(end -0.2794 -0.1778)
						)
						(arc
							(start -0.2794 0.1778)
							(mid -0.249642 0.249642)
							(end -0.1778 0.2794)
						)
						(arc
							(start 0.1778 0.2794)
							(mid 0.249642 0.249642)
							(end 0.2794 0.1778)
						)
						(arc
							(start 0.2794 -0.1778)
							(mid 0.249642 -0.249642)
							(end 0.1778 -0.2794)
						)
					)
					(width 0)
					(fill yes)
				)
			)
		)
	)
	(footprint ""
		(layer "F.Cu")
		(at 23.512272 -500.446548 180)
		(property "Reference" "PC27"
			(at 0 0 180)
			(layer "F.SilkS")
			(hide yes)
			(effects
				(font
					(size 1.27 1.27)
				)
			)
		)
		(property "Value" "SC22U25V5MX-GP"
			(at -0.0762 -6.1214 180)
			(unlocked yes)
			(layer "F.Fab")
			(hide yes)
			(effects
				(font
					(size 1.016 1.016)
					(thickness 0.1524)
				)
			)
		)
		(property "Device Type" "C805H58"
			(at -0.0762 -8.1534 180)
			(unlocked yes)
			(layer "F.Fab")
			(hide yes)
			(effects
				(font
					(size 1.016 1.016)
					(thickness 0.1524)
				)
			)
		)
		(duplicate_pad_numbers_are_jumpers no)
		(fp_line
			(start 0.635 0)
			(end -0.635 0)
			(stroke
				(width 0.508)
				(type default)
			)
			(layer "F.SilkS")
		)
		(fp_rect
			(start -0.9652 1.778)
			(end 0.9652 -1.778)
			(stroke
				(width 0)
				(type default)
			)
			(fill no)
			(layer "F.CrtYd")
		)
		(fp_poly
			(pts
				(xy -0.9652 -1.778) (xy 0.9652 -1.778) (xy 0.9652 1.778) (xy -0.9652 1.778)
			)
			(stroke
				(width 0)
				(type default)
			)
			(fill no)
			(layer "F.Fab")
		)
		(pad "1" smd rect
			(at 0 -0.9652 180)
			(size 1.397 1.143)
			(layers "F.Cu" "F.Mask" "F.Paste")
			(net "P5VC_12VIN")
		)
		(pad "2" smd rect
			(at 0 0.9652 180)
			(size 1.397 1.143)
			(layers "F.Cu" "F.Mask" "F.Paste")
			(net "GND")
		)
	)
	(footprint ""
		(layer "F.Cu")
		(at 37.083746 -436.5117 90)
		(property "Reference" "R253"
			(at 0 0 90)
			(layer "F.SilkS")
			(hide yes)
			(effects
				(font
					(size 1.27 1.27)
				)
			)
		)
		(property "Value" "0R2J-2-GP"
			(at 0.064008 -3.993896 90)
			(unlocked yes)
			(layer "F.Fab")
			(hide yes)
			(effects
				(font
					(size 1.016 1.016)
					(thickness 0.1524)
				)
			)
		)
		(property "Device Type" "R402H16"
			(at 0.064008 -5.517896 90)
			(unlocked yes)
			(layer "F.Fab")
			(hide yes)
			(effects
				(font
					(size 1.016 1.016)
					(thickness 0.1524)
				)
			)
		)
		(duplicate_pad_numbers_are_jumpers no)
		(fp_line
			(start 0.508 -0.9398)
			(end -0.508 -0.9398)
			(stroke
				(width 0.1524)
				(type default)
			)
			(layer "F.SilkS")
		)
		(fp_line
			(start -0.508 -0.9398)
			(end -0.508 0.9398)
			(stroke
				(width 0.1524)
				(type default)
			)
			(layer "F.SilkS")
		)
		(fp_rect
			(start -0.508 0.9398)
			(end 0.508 -0.9398)
			(stroke
				(width 0)
				(type default)
			)
			(fill no)
			(layer "F.CrtYd")
		)
		(fp_rect
			(start -0.508 0.9398)
			(end 0.508 -0.9398)
			(stroke
				(width 0)
				(type default)
			)
			(fill no)
			(layer "F.Fab")
		)
		(pad "1" smd custom
			(at 0 -0.4445 90)
			(size 0.1397 0.1397)
			(layers "F.Cu" "F.Mask" "F.Paste")
			(net "DRIVE_PWR10")
			(options
				(clearance outline)
				(anchor circle)
			)
			(primitives
				(gr_poly
					(pts
						(arc
							(start -0.1778 -0.2794)
							(mid -0.249642 -0.249642)
							(end -0.2794 -0.1778)
						)
						(arc
							(start -0.2794 0.1778)
							(mid -0.249642 0.249642)
							(end -0.1778 0.2794)
						)
						(arc
							(start 0.1778 0.2794)
							(mid 0.249642 0.249642)
							(end 0.2794 0.1778)
						)
						(arc
							(start 0.2794 -0.1778)
							(mid 0.249642 -0.249642)
							(end 0.1778 -0.2794)
						)
					)
					(width 0)
					(fill yes)
				)
			)
		)
		(pad "2" smd custom
			(at 0 0.4445 90)
			(size 0.1397 0.1397)
			(layers "F.Cu" "F.Mask" "F.Paste")
			(net "SW_PWR_HDD10")
			(options
				(clearance outline)
				(anchor circle)
			)
			(primitives
				(gr_poly
					(pts
						(arc
							(start -0.1778 -0.2794)
							(mid -0.249642 -0.249642)
							(end -0.2794 -0.1778)
						)
						(arc
							(start -0.2794 0.1778)
							(mid -0.249642 0.249642)
							(end -0.1778 0.2794)
						)
						(arc
							(start 0.1778 0.2794)
							(mid 0.249642 0.249642)
							(end 0.2794 0.1778)
						)
						(arc
							(start 0.2794 -0.1778)
							(mid 0.249642 -0.249642)
							(end 0.1778 -0.2794)
						)
					)
					(width 0)
					(fill yes)
				)
			)
		)
	)
	(footprint ""
		(layer "F.Cu")
		(at 200.037446 -458.377036 90)
		(property "Reference" "R352"
			(at 0 0 90)
			(layer "F.SilkS")
			(hide yes)
			(effects
				(font
					(size 1.27 1.27)
				)
			)
		)
		(property "Value" "0R2J-2-GP"
			(at 0.064008 -3.993896 90)
			(unlocked yes)
			(layer "F.Fab")
			(hide yes)
			(effects
				(font
					(size 1.016 1.016)
					(thickness 0.1524)
				)
			)
		)
		(property "Device Type" "R402H16"
			(at 0.064008 -5.517896 90)
			(unlocked yes)
			(layer "F.Fab")
			(hide yes)
			(effects
				(font
					(size 1.016 1.016)
					(thickness 0.1524)
				)
			)
		)
		(duplicate_pad_numbers_are_jumpers no)
		(fp_line
			(start 0.508 -0.9398)
			(end -0.508 -0.9398)
			(stroke
				(width 0.1524)
				(type default)
			)
			(layer "F.SilkS")
		)
		(fp_line
			(start -0.508 -0.9398)
			(end -0.508 0.9398)
			(stroke
				(width 0.1524)
				(type default)
			)
			(layer "F.SilkS")
		)
		(fp_rect
			(start -0.508 0.9398)
			(end 0.508 -0.9398)
			(stroke
				(width 0)
				(type default)
			)
			(fill no)
			(layer "F.CrtYd")
		)
		(fp_rect
			(start -0.508 0.9398)
			(end 0.508 -0.9398)
			(stroke
				(width 0)
				(type default)
			)
			(fill no)
			(layer "F.Fab")
		)
		(pad "1" smd custom
			(at 0 -0.4445 90)
			(size 0.1397 0.1397)
			(layers "F.Cu" "F.Mask" "F.Paste")
			(net "EEPROM_SCL")
			(options
				(clearance outline)
				(anchor circle)
			)
			(primitives
				(gr_poly
					(pts
						(arc
							(start -0.1778 -0.2794)
							(mid -0.249642 -0.249642)
							(end -0.2794 -0.1778)
						)
						(arc
							(start -0.2794 0.1778)
							(mid -0.249642 0.249642)
							(end -0.1778 0.2794)
						)
						(arc
							(start 0.1778 0.2794)
							(mid 0.249642 0.249642)
							(end 0.2794 0.1778)
						)
						(arc
							(start 0.2794 -0.1778)
							(mid 0.249642 -0.249642)
							(end 0.1778 -0.2794)
						)
					)
					(width 0)
					(fill yes)
				)
			)
		)
		(pad "2" smd custom
			(at 0 0.4445 90)
			(size 0.1397 0.1397)
			(layers "F.Cu" "F.Mask" "F.Paste")
			(net "I2C_B_SCL")
			(options
				(clearance outline)
				(anchor circle)
			)
			(primitives
				(gr_poly
					(pts
						(arc
							(start -0.1778 -0.2794)
							(mid -0.249642 -0.249642)
							(end -0.2794 -0.1778)
						)
						(arc
							(start -0.2794 0.1778)
							(mid -0.249642 0.249642)
							(end -0.1778 0.2794)
						)
						(arc
							(start 0.1778 0.2794)
							(mid 0.249642 0.249642)
							(end 0.2794 0.1778)
						)
						(arc
							(start 0.2794 -0.1778)
							(mid 0.249642 -0.249642)
							(end 0.1778 -0.2794)
						)
					)
					(width 0)
					(fill yes)
				)
			)
		)
	)
	(footprint ""
		(layer "F.Cu")
		(at 197.739 -281.686)
		(property "Reference" "C133"
			(at 0 0 0)
			(layer "F.SilkS")
			(hide yes)
			(effects
				(font
					(size 1.27 1.27)
				)
			)
		)
		(property "Value" "SCD1U10V2KX-5GP"
			(at 1.1811 -2.7051 0)
			(unlocked yes)
			(layer "F.Fab")
			(hide yes)
			(effects
				(font
					(size 1.016 1.016)
					(thickness 0.1524)
				)
			)
		)
		(property "Device Type" "C402H22"
			(at 1.1811 -4.2291 0)
			(unlocked yes)
			(layer "F.Fab")
			(hide yes)
			(effects
				(font
					(size 1.016 1.016)
					(thickness 0.1524)
				)
			)
		)
		(duplicate_pad_numbers_are_jumpers no)
		(fp_rect
			(start -0.4318 0.9525)
			(end 0.4318 -0.9525)
			(stroke
				(width 0)
				(type default)
			)
			(fill no)
			(layer "F.CrtYd")
		)
		(fp_rect
			(start -0.4318 0.9525)
			(end 0.4318 -0.9525)
			(stroke
				(width 0)
				(type default)
			)
			(fill no)
			(layer "F.Fab")
		)
		(pad "1" smd custom
			(at 0 -0.4445)
			(size 0.1524 0.1524)
			(layers "F.Cu" "F.Mask" "F.Paste")
			(net "P3V3")
			(options
				(clearance outline)
				(anchor circle)
			)
			(primitives
				(gr_poly
					(pts
						(arc
							(start 0.3048 -0.2032)
							(mid 0.275042 -0.275042)
							(end 0.2032 -0.3048)
						)
						(arc
							(start -0.2032 -0.3048)
							(mid -0.275042 -0.275042)
							(end -0.3048 -0.2032)
						)
						(arc
							(start -0.3048 0.2032)
							(mid -0.275042 0.275042)
							(end -0.2032 0.3048)
						)
						(arc
							(start 0.2032 0.3048)
							(mid 0.275042 0.275042)
							(end 0.3048 0.2032)
						)
					)
					(width 0)
					(fill yes)
				)
			)
		)
		(pad "2" smd custom
			(at 0 0.4445)
			(size 0.1524 0.1524)
			(layers "F.Cu" "F.Mask" "F.Paste")
			(net "GND")
			(options
				(clearance outline)
				(anchor circle)
			)
			(primitives
				(gr_poly
					(pts
						(arc
							(start 0.3048 -0.2032)
							(mid 0.275042 -0.275042)
							(end 0.2032 -0.3048)
						)
						(arc
							(start -0.2032 -0.3048)
							(mid -0.275042 -0.275042)
							(end -0.3048 -0.2032)
						)
						(arc
							(start -0.3048 0.2032)
							(mid -0.275042 0.275042)
							(end -0.2032 0.3048)
						)
						(arc
							(start 0.2032 0.3048)
							(mid 0.275042 0.275042)
							(end 0.3048 0.2032)
						)
					)
					(width 0)
					(fill yes)
				)
			)
		)
	)
	(footprint ""
		(layer "F.Cu")
		(at 202.564746 -185.9407 -90)
		(property "Reference" "R435"
			(at 0 0 270)
			(layer "F.SilkS")
			(hide yes)
			(effects
				(font
					(size 1.27 1.27)
				)
			)
		)
		(property "Value" "4K7R2J-2-GP"
			(at 0.064008 -3.993896 270)
			(unlocked yes)
			(layer "F.Fab")
			(hide yes)
			(effects
				(font
					(size 1.016 1.016)
					(thickness 0.1524)
				)
			)
		)
		(property "Device Type" "R402H16"
			(at 0.064008 -5.517896 270)
			(unlocked yes)
			(layer "F.Fab")
			(hide yes)
			(effects
				(font
					(size 1.016 1.016)
					(thickness 0.1524)
				)
			)
		)
		(duplicate_pad_numbers_are_jumpers no)
		(fp_line
			(start -0.508 -0.9398)
			(end -0.508 0.9398)
			(stroke
				(width 0.1524)
				(type default)
			)
			(layer "F.SilkS")
		)
		(fp_line
			(start 0.508 -0.9398)
			(end -0.508 -0.9398)
			(stroke
				(width 0.1524)
				(type default)
			)
			(layer "F.SilkS")
		)
		(fp_rect
			(start -0.508 0.9398)
			(end 0.508 -0.9398)
			(stroke
				(width 0)
				(type default)
			)
			(fill no)
			(layer "F.CrtYd")
		)
		(fp_rect
			(start -0.508 0.9398)
			(end 0.508 -0.9398)
			(stroke
				(width 0)
				(type default)
			)
			(fill no)
			(layer "F.Fab")
		)
		(pad "1" smd custom
			(at 0 -0.4445 270)
			(size 0.1397 0.1397)
			(layers "F.Cu" "F.Mask" "F.Paste")
			(net "P3V3")
			(options
				(clearance outline)
				(anchor circle)
			)
			(primitives
				(gr_poly
					(pts
						(arc
							(start -0.1778 -0.2794)
							(mid -0.249642 -0.249642)
							(end -0.2794 -0.1778)
						)
						(arc
							(start -0.2794 0.1778)
							(mid -0.249642 0.249642)
							(end -0.1778 0.2794)
						)
						(arc
							(start 0.1778 0.2794)
							(mid 0.249642 0.249642)
							(end 0.2794 0.1778)
						)
						(arc
							(start 0.2794 -0.1778)
							(mid 0.249642 -0.249642)
							(end 0.1778 -0.2794)
						)
					)
					(width 0)
					(fill yes)
				)
			)
		)
		(pad "2" smd custom
			(at 0 0.4445 270)
			(size 0.1397 0.1397)
			(layers "F.Cu" "F.Mask" "F.Paste")
			(net "SAS2X28_B_HDD3_FLT")
			(options
				(clearance outline)
				(anchor circle)
			)
			(primitives
				(gr_poly
					(pts
						(arc
							(start -0.1778 -0.2794)
							(mid -0.249642 -0.249642)
							(end -0.2794 -0.1778)
						)
						(arc
							(start -0.2794 0.1778)
							(mid -0.249642 0.249642)
							(end -0.1778 0.2794)
						)
						(arc
							(start 0.1778 0.2794)
							(mid 0.249642 0.249642)
							(end 0.2794 0.1778)
						)
						(arc
							(start 0.2794 -0.1778)
							(mid 0.249642 -0.249642)
							(end 0.1778 -0.2794)
						)
					)
					(width 0)
					(fill yes)
				)
			)
		)
	)
	(footprint ""
		(layer "F.Cu")
		(at 46.964346 -38.608 -90)
		(property "Reference" "R499"
			(at 0 0 270)
			(layer "F.SilkS")
			(hide yes)
			(effects
				(font
					(size 1.27 1.27)
				)
			)
		)
		(property "Value" "1KR2F-3-GP"
			(at 0.064008 -3.993896 270)
			(unlocked yes)
			(layer "F.Fab")
			(hide yes)
			(effects
				(font
					(size 1.016 1.016)
					(thickness 0.1524)
				)
			)
		)
		(property "Device Type" "R402H16"
			(at 0.064008 -5.517896 270)
			(unlocked yes)
			(layer "F.Fab")
			(hide yes)
			(effects
				(font
					(size 1.016 1.016)
					(thickness 0.1524)
				)
			)
		)
		(duplicate_pad_numbers_are_jumpers no)
		(fp_line
			(start -0.508 -0.9398)
			(end -0.508 0.9398)
			(stroke
				(width 0.1524)
				(type default)
			)
			(layer "F.SilkS")
		)
		(fp_line
			(start 0.508 -0.9398)
			(end -0.508 -0.9398)
			(stroke
				(width 0.1524)
				(type default)
			)
			(layer "F.SilkS")
		)
		(fp_rect
			(start -0.508 0.9398)
			(end 0.508 -0.9398)
			(stroke
				(width 0)
				(type default)
			)
			(fill no)
			(layer "F.CrtYd")
		)
		(fp_rect
			(start -0.508 0.9398)
			(end 0.508 -0.9398)
			(stroke
				(width 0)
				(type default)
			)
			(fill no)
			(layer "F.Fab")
		)
		(pad "1" smd custom
			(at 0 -0.4445 270)
			(size 0.1397 0.1397)
			(layers "F.Cu" "F.Mask" "F.Paste")
			(net "FLT_HDD9_B")
			(options
				(clearance outline)
				(anchor circle)
			)
			(primitives
				(gr_poly
					(pts
						(arc
							(start -0.1778 -0.2794)
							(mid -0.249642 -0.249642)
							(end -0.2794 -0.1778)
						)
						(arc
							(start -0.2794 0.1778)
							(mid -0.249642 0.249642)
							(end -0.1778 0.2794)
						)
						(arc
							(start 0.1778 0.2794)
							(mid 0.249642 0.249642)
							(end 0.2794 0.1778)
						)
						(arc
							(start 0.2794 -0.1778)
							(mid 0.249642 -0.249642)
							(end 0.1778 -0.2794)
						)
					)
					(width 0)
					(fill yes)
				)
			)
		)
		(pad "2" smd custom
			(at 0 0.4445 270)
			(size 0.1397 0.1397)
			(layers "F.Cu" "F.Mask" "F.Paste")
			(net "FLT_HDD9_DRIVE")
			(options
				(clearance outline)
				(anchor circle)
			)
			(primitives
				(gr_poly
					(pts
						(arc
							(start -0.1778 -0.2794)
							(mid -0.249642 -0.249642)
							(end -0.2794 -0.1778)
						)
						(arc
							(start -0.2794 0.1778)
							(mid -0.249642 0.249642)
							(end -0.1778 0.2794)
						)
						(arc
							(start 0.1778 0.2794)
							(mid 0.249642 0.249642)
							(end 0.2794 0.1778)
						)
						(arc
							(start 0.2794 -0.1778)
							(mid 0.249642 -0.249642)
							(end 0.1778 -0.2794)
						)
					)
					(width 0)
					(fill yes)
				)
			)
		)
	)
	(footprint ""
		(layer "F.Cu")
		(at 34.6964 -299.0596 180)
		(property "Reference" "C227"
			(at 0 0 180)
			(layer "F.SilkS")
			(hide yes)
			(effects
				(font
					(size 1.27 1.27)
				)
			)
		)
		(property "Value" "SC1U25V3KX-1-GP"
			(at 0 -2.8194 180)
			(unlocked yes)
			(layer "F.Fab")
			(hide yes)
			(effects
				(font
					(size 1.016 1.016)
					(thickness 0.1524)
				)
			)
		)
		(property "Device Type" "C603H36"
			(at 0 -4.3434 180)
			(unlocked yes)
			(layer "F.Fab")
			(hide yes)
			(effects
				(font
					(size 1.016 1.016)
					(thickness 0.1524)
				)
			)
		)
		(duplicate_pad_numbers_are_jumpers no)
		(fp_line
			(start 0.508 0)
			(end -0.508 0)
			(stroke
				(width 0.2032)
				(type default)
			)
			(layer "F.SilkS")
		)
		(fp_rect
			(start -0.5842 1.3335)
			(end 0.5842 -1.3335)
			(stroke
				(width 0)
				(type default)
			)
			(fill no)
			(layer "F.CrtYd")
		)
		(fp_rect
			(start -0.5842 1.3335)
			(end 0.5842 -1.3335)
			(stroke
				(width 0)
				(type default)
			)
			(fill no)
			(layer "F.Fab")
		)
		(pad "1" smd custom
			(at 0 -0.762 180)
			(size 0.2159 0.2159)
			(layers "F.Cu" "F.Mask" "F.Paste")
			(net "P12V_HDD7")
			(options
				(clearance outline)
				(anchor circle)
			)
			(primitives
				(gr_poly
					(pts
						(arc
							(start -0.3302 -0.4318)
							(mid -0.402042 -0.402042)
							(end -0.4318 -0.3302)
						)
						(arc
							(start -0.4318 0.3302)
							(mid -0.402042 0.402042)
							(end -0.3302 0.4318)
						)
						(arc
							(start 0.3302 0.4318)
							(mid 0.402042 0.402042)
							(end 0.4318 0.3302)
						)
						(arc
							(start 0.4318 -0.3302)
							(mid 0.402042 -0.402042)
							(end 0.3302 -0.4318)
						)
					)
					(width 0)
					(fill yes)
				)
			)
		)
		(pad "2" smd custom
			(at 0 0.762 180)
			(size 0.2159 0.2159)
			(layers "F.Cu" "F.Mask" "F.Paste")
			(net "GND")
			(options
				(clearance outline)
				(anchor circle)
			)
			(primitives
				(gr_poly
					(pts
						(arc
							(start -0.3302 -0.4318)
							(mid -0.402042 -0.402042)
							(end -0.4318 -0.3302)
						)
						(arc
							(start -0.4318 0.3302)
							(mid -0.402042 0.402042)
							(end -0.3302 0.4318)
						)
						(arc
							(start 0.3302 0.4318)
							(mid 0.402042 0.402042)
							(end 0.4318 0.3302)
						)
						(arc
							(start 0.4318 -0.3302)
							(mid 0.402042 -0.402042)
							(end 0.3302 -0.4318)
						)
					)
					(width 0)
					(fill yes)
				)
			)
		)
	)
)
